# S9S_MB_2U (Grand Teton) — schematic netlist excerpt (pin names and nets, part order shuffled) for the footprints in the layout excerpt that follows; sources: Cadence DE-HDL packaged netlist, KiCad conversion of 03242023_DA0F0TMBIJ0_F0T_Motherboard_J_brd_V01_OCP.brd

R66  Q_RES  100 1% CHIP  pkg 0402LF  page 44 : A = JTAG_DBP_CPU_QS_GTL_TMS ; B = JTAG_DBP_CPU1_QS_GTL_R_TMS
C7  Q_CAP  10UF 16V 10% X6S  pkg C0805  page 83 : A = P12V_S3_AUX_CPU0_NVDIMM ; B = GND
PC612_P0_1  Q_CAP  100NF 50V 10% X7R  pkg C0402  page 271 : A = PVCCFA_EHV_FIVRA_CPU0 ; B = GND

(kicad_pcb
	(version 20260206)
	(generator "pcbnew")
	(generator_version "10.0")
	(general
		(thickness 1.6)
		(legacy_teardrops no)
	)
	(paper "A4")
	(title_block
		(title "03242023_DA0F0TMBIJ0_F0T_Motherboard_J_brd_V01_OCP.brd")
		(comment 1 "Grand Teton / footprints 4343-4345 of 6105")
	)
	(layers
		(0 "F.Cu" signal "TOP")
		(4 "In1.Cu" signal "GND")
		(6 "In2.Cu" signal "IN1")
		(8 "In3.Cu" signal "GND1")
		(10 "In4.Cu" signal "IN2")
		(12 "In5.Cu" signal "GND2")
		(14 "In6.Cu" signal "IN3")
		(16 "In7.Cu" signal "GND3")
		(18 "In8.Cu" signal "VCC")
		(20 "In9.Cu" signal "VCC1")
		(22 "In10.Cu" signal "GND4")
		(24 "In11.Cu" signal "IN4")
		(26 "In12.Cu" signal "GND5")
		(28 "In13.Cu" signal "IN5")
		(30 "In14.Cu" signal "GND6")
		(32 "In15.Cu" signal "IN6")
		(34 "In16.Cu" signal "GND7")
		(2 "B.Cu" signal "BOTTOM")
		(9 "F.Adhes" user "F.Adhesive")
		(11 "B.Adhes" user "B.Adhesive")
		(13 "F.Paste" user "Package Geometry/Pastemask Top")
		(15 "B.Paste" user "Package Geometry/Pastemask Bottom")
		(5 "F.SilkS" user "Ref Des/Silkscreen Top")
		(7 "B.SilkS" user "Ref Des/Silkscreen Bottom")
		(1 "F.Mask" user "Board Geometry/Soldermask Top")
		(3 "B.Mask" user "Board Geometry/Soldermask Bottom")
		(17 "Dwgs.User" user "User.Drawings")
		(19 "Cmts.User" user "User.Comments")
		(21 "Eco1.User" user "User.Eco1")
		(23 "Eco2.User" user "User.Eco2")
		(25 "Edge.Cuts" user "Board Geometry/Outline")
		(27 "Margin" user)
		(31 "F.CrtYd" user "Package Geometry/Place Bound Top")
		(29 "B.CrtYd" user "Package Geometry/Place Bound Bottom")
		(35 "F.Fab" user "Ref Des/Assembly Top")
		(33 "B.Fab" user "Ref Des/Assembly Bottom")
	)
	(footprint ""
		(layer "B.Cu")
		(at 421.138604 -353.117404 -90)
		(property "Reference" "PC612_P0_1"
			(at 0 0 90)
			(layer "B.SilkS")
			(hide yes)
			(effects
				(font
					(size 1.27 1.27)
				)
				(justify mirror)
			)
		)
		(property "Value" ""
			(at 0 0 90)
			(layer "B.Fab")
			(effects
				(font
					(size 1.27 1.27)
				)
				(justify mirror)
			)
		)
		(duplicate_pad_numbers_are_jumpers no)
		(fp_line
			(start -0.7874 0.4064)
			(end 0.7874 0.4064)
			(stroke
				(width 0.1524)
				(type default)
			)
			(layer "B.SilkS")
		)
		(fp_line
			(start 0.7874 0.4064)
			(end 0.7874 -0.4064)
			(stroke
				(width 0.1524)
				(type default)
			)
			(layer "B.SilkS")
		)
		(fp_line
			(start -0.7874 -0.4064)
			(end -0.7874 0.4064)
			(stroke
				(width 0.1524)
				(type default)
			)
			(layer "B.SilkS")
		)
		(fp_line
			(start 0.7874 -0.4064)
			(end -0.7874 -0.4064)
			(stroke
				(width 0.1524)
				(type default)
			)
			(layer "B.SilkS")
		)
		(fp_line
			(start -0.67945 0.3048)
			(end -0.120396 0.3048)
			(stroke
				(width 0.1)
				(type default)
			)
			(layer "B.Fab")
		)
		(fp_line
			(start -0.120396 0.3048)
			(end -0.120396 0.2794)
			(stroke
				(width 0.1)
				(type default)
			)
			(layer "B.Fab")
		)
		(fp_line
			(start 0.12065 0.3048)
			(end 0.67945 0.3048)
			(stroke
				(width 0.1)
				(type default)
			)
			(layer "B.Fab")
		)
		(fp_line
			(start 0.67945 0.3048)
			(end 0.67945 -0.305054)
			(stroke
				(width 0.1)
				(type default)
			)
			(layer "B.Fab")
		)
		(fp_line
			(start -0.120396 0.2794)
			(end 0.12065 0.2794)
			(stroke
				(width 0.1)
				(type default)
			)
			(layer "B.Fab")
		)
		(fp_line
			(start 0.12065 0.2794)
			(end 0.12065 0.3048)
			(stroke
				(width 0.1)
				(type default)
			)
			(layer "B.Fab")
		)
		(fp_line
			(start -0.12065 -0.2794)
			(end -0.12065 -0.3048)
			(stroke
				(width 0.1)
				(type default)
			)
			(layer "B.Fab")
		)
		(fp_line
			(start 0.12065 -0.2794)
			(end -0.12065 -0.2794)
			(stroke
				(width 0.1)
				(type default)
			)
			(layer "B.Fab")
		)
		(fp_line
			(start -0.67945 -0.3048)
			(end -0.67945 0.3048)
			(stroke
				(width 0.1)
				(type default)
			)
			(layer "B.Fab")
		)
		(fp_line
			(start -0.12065 -0.3048)
			(end -0.67945 -0.3048)
			(stroke
				(width 0.1)
				(type default)
			)
			(layer "B.Fab")
		)
		(fp_line
			(start 0.12065 -0.305054)
			(end 0.12065 -0.2794)
			(stroke
				(width 0.1)
				(type default)
			)
			(layer "B.Fab")
		)
		(fp_line
			(start 0.67945 -0.305054)
			(end 0.12065 -0.305054)
			(stroke
				(width 0.1)
				(type default)
			)
			(layer "B.Fab")
		)
		(pad "1" smd circle
			(at 0.40005 0 90)
			(size 0 0)
			(layers "B.Cu" "B.Mask" "B.Paste")
			(net "PVCCFA_EHV_FIVRA_CPU0")
		)
		(pad "2" smd circle
			(at -0.40005 0 90)
			(size 0 0)
			(layers "B.Cu" "B.Mask" "B.Paste")
			(net "GND")
		)
	)
	(footprint ""
		(layer "B.Cu")
		(at 86.473284 -190.705232 -90)
		(property "Reference" "R66"
			(at 0 0 90)
			(layer "B.SilkS")
			(hide yes)
			(effects
				(font
					(size 1.27 1.27)
				)
				(justify mirror)
			)
		)
		(property "Value" ""
			(at 0 0 90)
			(layer "B.Fab")
			(effects
				(font
					(size 1.27 1.27)
				)
				(justify mirror)
			)
		)
		(duplicate_pad_numbers_are_jumpers no)
		(fp_line
			(start -0.7874 0.4064)
			(end 0.7874 0.4064)
			(stroke
				(width 0.1524)
				(type default)
			)
			(layer "B.SilkS")
		)
		(fp_line
			(start 0.7874 0.4064)
			(end 0.7874 -0.4064)
			(stroke
				(width 0.1524)
				(type default)
			)
			(layer "B.SilkS")
		)
		(fp_line
			(start -0.7874 -0.4064)
			(end -0.7874 0.4064)
			(stroke
				(width 0.1524)
				(type default)
			)
			(layer "B.SilkS")
		)
		(fp_line
			(start 0.7874 -0.4064)
			(end -0.7874 -0.4064)
			(stroke
				(width 0.1524)
				(type default)
			)
			(layer "B.SilkS")
		)
		(fp_line
			(start -0.67945 0.3048)
			(end -0.120396 0.3048)
			(stroke
				(width 0.1)
				(type default)
			)
			(layer "B.Fab")
		)
		(fp_line
			(start -0.120396 0.3048)
			(end -0.120396 0.2794)
			(stroke
				(width 0.1)
				(type default)
			)
			(layer "B.Fab")
		)
		(fp_line
			(start 0.12065 0.3048)
			(end 0.67945 0.3048)
			(stroke
				(width 0.1)
				(type default)
			)
			(layer "B.Fab")
		)
		(fp_line
			(start 0.67945 0.3048)
			(end 0.67945 -0.305054)
			(stroke
				(width 0.1)
				(type default)
			)
			(layer "B.Fab")
		)
		(fp_line
			(start -0.120396 0.2794)
			(end 0.12065 0.2794)
			(stroke
				(width 0.1)
				(type default)
			)
			(layer "B.Fab")
		)
		(fp_line
			(start 0.12065 0.2794)
			(end 0.12065 0.3048)
			(stroke
				(width 0.1)
				(type default)
			)
			(layer "B.Fab")
		)
		(fp_line
			(start -0.12065 -0.2794)
			(end -0.12065 -0.3048)
			(stroke
				(width 0.1)
				(type default)
			)
			(layer "B.Fab")
		)
		(fp_line
			(start 0.12065 -0.2794)
			(end -0.12065 -0.2794)
			(stroke
				(width 0.1)
				(type default)
			)
			(layer "B.Fab")
		)
		(fp_line
			(start -0.67945 -0.3048)
			(end -0.67945 0.3048)
			(stroke
				(width 0.1)
				(type default)
			)
			(layer "B.Fab")
		)
		(fp_line
			(start -0.12065 -0.3048)
			(end -0.67945 -0.3048)
			(stroke
				(width 0.1)
				(type default)
			)
			(layer "B.Fab")
		)
		(fp_line
			(start 0.12065 -0.305054)
			(end 0.12065 -0.2794)
			(stroke
				(width 0.1)
				(type default)
			)
			(layer "B.Fab")
		)
		(fp_line
			(start 0.67945 -0.305054)
			(end 0.12065 -0.305054)
			(stroke
				(width 0.1)
				(type default)
			)
			(layer "B.Fab")
		)
		(pad "1" smd circle
			(at 0.40005 0 90)
			(size 0 0)
			(layers "B.Cu" "B.Mask" "B.Paste")
			(net "JTAG_DBP_CPU_QS_GTL_TMS")
		)
		(pad "2" smd circle
			(at -0.40005 0 90)
			(size 0 0)
			(layers "B.Cu" "B.Mask" "B.Paste")
			(net "JTAG_DBP_CPU1_QS_GTL_R_TMS")
		)
	)
	(footprint ""
		(layer "B.Cu")
		(at 308.899814 -321.549776 -90)
		(property "Reference" "C7"
			(at 0 0 90)
			(layer "B.SilkS")
			(hide yes)
			(effects
				(font
					(size 1.27 1.27)
				)
				(justify mirror)
			)
		)
		(property "Value" ""
			(at 0 0 90)
			(layer "B.Fab")
			(effects
				(font
					(size 1.27 1.27)
				)
				(justify mirror)
			)
		)
		(duplicate_pad_numbers_are_jumpers no)
		(fp_line
			(start -1.524 0.762)
			(end 1.524 0.762)
			(stroke
				(width 0.1524)
				(type default)
			)
			(layer "B.SilkS")
		)
		(fp_line
			(start 1.524 0.762)
			(end 1.524 -0.762)
			(stroke
				(width 0.1524)
				(type default)
			)
			(layer "B.SilkS")
		)
		(fp_line
			(start -1.524 -0.762)
			(end -1.524 0.762)
			(stroke
				(width 0.1524)
				(type default)
			)
			(layer "B.SilkS")
		)
		(fp_line
			(start 1.524 -0.762)
			(end -1.524 -0.762)
			(stroke
				(width 0.1524)
				(type default)
			)
			(layer "B.SilkS")
		)
		(fp_line
			(start -1.1049 0.724916)
			(end -1.1049 -0.724916)
			(stroke
				(width 0.1)
				(type default)
			)
			(layer "B.Fab")
		)
		(fp_line
			(start 1.1049 0.724916)
			(end -1.1049 0.724916)
			(stroke
				(width 0.1)
				(type default)
			)
			(layer "B.Fab")
		)
		(fp_line
			(start -1.1049 -0.724916)
			(end 1.1049 -0.724916)
			(stroke
				(width 0.1)
				(type default)
			)
			(layer "B.Fab")
		)
		(fp_line
			(start 1.1049 -0.724916)
			(end 1.1049 0.724916)
			(stroke
				(width 0.1)
				(type default)
			)
			(layer "B.Fab")
		)
		(pad "1" smd rect
			(at 0.889 0 270)
			(size 1.016 1.27)
			(layers "B.Cu" "B.Mask" "B.Paste")
			(net "P12V_S3_AUX_CPU0_NVDIMM")
		)
		(pad "2" smd rect
			(at -0.889 0 270)
			(size 1.016 1.27)
			(layers "B.Cu" "B.Mask" "B.Paste")
			(net "GND")
		)
	)
)
